(kicad_pcb
	(version 20241229)
	(generator "pcbnew")
	(generator_version "9.0")
	(general
		(thickness 1.62)
		(legacy_teardrops no)
	)
	(paper "A4")
	(title_block
		(title "OCuLink to 10GbE adapter")
		(date "2026-02-23")
		(rev "1.1.0")
		(company "Antmicro Ltd")
		(comment 1 "www.antmicro.com")
		(comment 9 "footprints 259-263 of 510")
	)
	(layers
		(0 "F.Cu" signal)
		(4 "In1.Cu" signal)
		(6 "In2.Cu" signal)
		(8 "In3.Cu" signal)
		(10 "In4.Cu" signal)
		(12 "In5.Cu" signal)
		(14 "In6.Cu" signal)
		(2 "B.Cu" signal)
		(9 "F.Adhes" user "F.Adhesive")
		(11 "B.Adhes" user "B.Adhesive")
		(13 "F.Paste" user)
		(15 "B.Paste" user)
		(5 "F.SilkS" user "F.Silkscreen")
		(7 "B.SilkS" user "B.Silkscreen")
		(1 "F.Mask" user)
		(3 "B.Mask" user)
		(17 "Dwgs.User" user "User.Drawings")
		(19 "Cmts.User" user "User.Comments")
		(21 "Eco1.User" user "User.Eco1")
		(23 "Eco2.User" user "User.Eco2")
		(25 "Edge.Cuts" user)
		(27 "Margin" user)
		(31 "F.CrtYd" user "F.Courtyard")
		(29 "B.CrtYd" user "B.Courtyard")
		(35 "F.Fab" user)
		(33 "B.Fab" user)
	)
	(footprint "antmicro-footprints:L_WE-PMFI-353220"
		(layer "F.Cu")
		(at 70.7 83.589996 -90)
		(descr "https://www.we-online.com/en/components/products/WE-PMFI#/articles/WE-PMFI-353220")
		(property "Reference" "L1"
			(at 2.410004 2 0)
			(unlocked yes)
			(layer "F.SilkS")
			(effects
				(font
					(size 0.7 0.7)
					(thickness 0.15)
				)
				(justify left top)
			)
		)
		(property "Value" "L_2u2_5.8A_WE-PMFI-35329222"
			(at -2.600001 3.1 270)
			(unlocked yes)
			(layer "F.Fab")
			(hide yes)
			(effects
				(font
					(size 0.7 0.7)
					(thickness 0.15)
				)
				(justify left bottom)
			)
		)
		(property "Datasheet" "https://www.we-online.com/components/products/datasheet/74479335329222.pdf"
			(at 0 0 90)
			(layer "F.Fab")
			(hide yes)
			(effects
				(font
					(size 0.7 0.7)
					(thickness 0.15)
				)
				(justify right top)
			)
		)
		(property "Description" "Power Inductors - SMD WE-PMFI 2.2 uH 5.8 A 40 mOhms AEC-Q200"
			(at 0 0 90)
			(layer "F.Fab")
			(hide yes)
			(effects
				(font
					(size 0.7 0.7)
					(thickness 0.15)
				)
				(justify right top)
			)
		)
		(property "Val" "2u2/5.8A"
			(at 0 0 270)
			(unlocked yes)
			(layer "F.Fab")
			(hide yes)
			(effects
				(font
					(size 1 1)
					(thickness 0.15)
				)
			)
		)
		(property "Manufacturer" "Würth Elektronik"
			(at 0 0 270)
			(unlocked yes)
			(layer "F.Fab")
			(hide yes)
			(effects
				(font
					(size 1 1)
					(thickness 0.15)
				)
			)
		)
		(property "MPN" "74479335329222"
			(at 0 0 270)
			(unlocked yes)
			(layer "F.Fab")
			(hide yes)
			(effects
				(font
					(size 1 1)
					(thickness 0.15)
				)
			)
		)
		(property "ISat" "7.8A"
			(at 0 0 270)
			(unlocked yes)
			(layer "F.Fab")
			(hide yes)
			(effects
				(font
					(size 1 1)
					(thickness 0.15)
				)
			)
		)
		(property "IMax" "5.8A"
			(at 0 0 270)
			(unlocked yes)
			(layer "F.Fab")
			(hide yes)
			(effects
				(font
					(size 1 1)
					(thickness 0.15)
				)
			)
		)
		(property "Size" "3.5x3.2x2.0"
			(at 0 0 270)
			(unlocked yes)
			(layer "F.Fab")
			(hide yes)
			(effects
				(font
					(size 1 1)
					(thickness 0.15)
				)
			)
		)
		(property "Author" "Antmicro"
			(at 0 0 270)
			(unlocked yes)
			(layer "F.Fab")
			(hide yes)
			(effects
				(font
					(size 1 1)
					(thickness 0.15)
				)
			)
		)
		(property "License" "Apache-2.0"
			(at 0 0 270)
			(unlocked yes)
			(layer "F.Fab")
			(hide yes)
			(effects
				(font
					(size 1 1)
					(thickness 0.15)
				)
			)
		)
		(sheetname "/Power/")
		(sheetfile "power.kicad_sch")
		(attr smd)
		(fp_line
			(start -1.75 1.85)
			(end 1.75 1.85)
			(stroke
				(width 0.15)
				(type solid)
			)
			(layer "F.SilkS")
		)
		(fp_line
			(start -1.75 -1.85)
			(end 1.75 -1.85)
			(stroke
				(width 0.15)
				(type solid)
			)
			(layer "F.SilkS")
		)
		(fp_rect
			(start -2.25 -2)
			(end 2.25 2)
			(stroke
				(width 0.05)
				(type solid)
			)
			(fill no)
			(layer "F.CrtYd")
		)
		(fp_rect
			(start -1.75 -1.6)
			(end 1.75 1.6)
			(stroke
				(width 0.15)
				(type solid)
			)
			(fill no)
			(layer "F.Fab")
		)
		(pad "1" smd rect
			(at -1.5 0 270)
			(size 1 3.5)
			(layers "F.Cu" "F.Mask" "F.Paste")
			(net 333 "/Power/3V3_SW")
			(pintype "passive")
		)
		(pad "2" smd rect
			(at 1.5 0 270)
			(size 1 3.5)
			(layers "F.Cu" "F.Mask" "F.Paste")
			(net 255 "/Power/+3V3_OUT")
			(pintype "passive")
		)
	)
	(footprint "antmicro-footprints:C_0402_1005Metric"
		(layer "F.Cu")
		(at 70.66 68.38)
		(descr "Capacitor SMD 0402")
		(tags "capacitor SMD 0402")
		(property "Reference" "C201"
			(at 0.95 0.47 0)
			(layer "F.SilkS")
			(effects
				(font
					(size 0.7 0.7)
					(thickness 0.15)
				)
				(justify left bottom)
			)
		)
		(property "Value" "C_1u_25V_0402"
			(at -1.022927 2.155213 0)
			(layer "F.Fab")
			(hide yes)
			(effects
				(font
					(size 0.7 0.7)
					(thickness 0.15)
				)
				(justify left bottom)
			)
		)
		(property "Datasheet" "https://www.murata.com/products/productdetail?partno=GRM155R61E105KE11%23"
			(at 0 0 0)
			(layer "F.Fab")
			(hide yes)
			(effects
				(font
					(size 1.27 1.27)
					(thickness 0.15)
				)
			)
		)
		(property "Description" "SMD Multilayer Ceramic Capacitor, 1 µF, 25 V, 0402 [1005 Metric], ± 10%, X5R, GRM Series"
			(at 0 0 0)
			(layer "F.Fab")
			(hide yes)
			(effects
				(font
					(size 1.27 1.27)
					(thickness 0.15)
				)
			)
		)
		(property "MPN" "GRM155R61E105KE11J"
			(at 0 0 0)
			(unlocked yes)
			(layer "F.Fab")
			(hide yes)
			(effects
				(font
					(size 1 1)
					(thickness 0.15)
				)
			)
		)
		(property "Manufacturer" "Murata"
			(at 0 0 0)
			(unlocked yes)
			(layer "F.Fab")
			(hide yes)
			(effects
				(font
					(size 1 1)
					(thickness 0.15)
				)
			)
		)
		(property "License" "Apache-2.0"
			(at 0 0 0)
			(unlocked yes)
			(layer "F.Fab")
			(hide yes)
			(effects
				(font
					(size 1 1)
					(thickness 0.15)
				)
			)
		)
		(property "Author" "Antmicro"
			(at 0 0 0)
			(unlocked yes)
			(layer "F.Fab")
			(hide yes)
			(effects
				(font
					(size 1 1)
					(thickness 0.15)
				)
			)
		)
		(property "Val" "1u"
			(at 0 0 0)
			(unlocked yes)
			(layer "F.Fab")
			(hide yes)
			(effects
				(font
					(size 1 1)
					(thickness 0.15)
				)
			)
		)
		(property "Voltage" "25V"
			(at 0 0 0)
			(unlocked yes)
			(layer "F.Fab")
			(hide yes)
			(effects
				(font
					(size 1 1)
					(thickness 0.15)
				)
			)
		)
		(property "Dielectric" "X5R"
			(at 0 0 0)
			(unlocked yes)
			(layer "F.Fab")
			(hide yes)
			(effects
				(font
					(size 1 1)
					(thickness 0.15)
				)
			)
		)
		(sheetname "/Power/Ideal diode 1/")
		(sheetfile "ideal-diode.kicad_sch")
		(attr smd)
		(fp_rect
			(start -0.925 -0.47)
			(end 0.925 0.47)
			(stroke
				(width 0.05)
				(type default)
			)
			(fill no)
			(layer "F.CrtYd")
		)
		(fp_line
			(start -0.494 -0.25)
			(end 0.504 -0.25)
			(stroke
				(width 0.15)
				(type solid)
			)
			(layer "F.Fab")
		)
		(fp_line
			(start -0.494 0.248)
			(end -0.494 -0.25)
			(stroke
				(width 0.15)
				(type solid)
			)
			(layer "F.Fab")
		)
		(fp_line
			(start 0.504 -0.25)
			(end 0.504 0.248)
			(stroke
				(width 0.15)
				(type solid)
			)
			(layer "F.Fab")
		)
		(fp_line
			(start 0.504 0.248)
			(end -0.494 0.248)
			(stroke
				(width 0.15)
				(type solid)
			)
			(layer "F.Fab")
		)
		(pad "1" smd roundrect
			(at -0.48 0)
			(size 0.59 0.64)
			(layers "F.Cu" "F.Mask" "F.Paste")
			(roundrect_rratio 0.25)
			(net 28 "GND")
			(pintype "passive")
		)
		(pad "2" smd roundrect
			(at 0.48 0)
			(size 0.59 0.64)
			(layers "F.Cu" "F.Mask" "F.Paste")
			(roundrect_rratio 0.25)
			(net 314 "VCC")
			(pintype "passive")
		)
	)
	(footprint "antmicro-footprints:C_0603_1608Metric_EIA"
		(layer "F.Cu")
		(at 73.549997 86.459996 90)
		(descr "Capacitor SMD 0603, IPC-7351 Density Level A")
		(tags "Capacitor 0603")
		(property "Reference" "C8"
			(at -2.520004 0.410003 90)
			(layer "F.SilkS")
			(effects
				(font
					(size 0.7 0.7)
					(thickness 0.15)
				)
				(justify left bottom)
			)
		)
		(property "Value" "C_22u_16V_0603"
			(at -1.42757 1.770288 90)
			(layer "F.Fab")
			(hide yes)
			(effects
				(font
					(size 0.7 0.7)
					(thickness 0.15)
				)
				(justify left bottom)
			)
		)
		(property "Datasheet" "https://product.samsungsem.com/mlcc/CL10A226MO7JZN.do"
			(at 0 0 90)
			(layer "F.Fab")
			(hide yes)
			(effects
				(font
					(size 1.27 1.27)
					(thickness 0.15)
				)
			)
		)
		(property "Description" "SMD Multilayer Ceramic Capacitor"
			(at 0 0 90)
			(layer "F.Fab")
			(hide yes)
			(effects
				(font
					(size 1.27 1.27)
					(thickness 0.15)
				)
			)
		)
		(property "MPN" "CL10A226MO7JZNC"
			(at 0 0 90)
			(unlocked yes)
			(layer "F.Fab")
			(hide yes)
			(effects
				(font
					(size 1 1)
					(thickness 0.15)
				)
			)
		)
		(property "Manufacturer" "Samsung Electro-Mechanics"
			(at 0 0 90)
			(unlocked yes)
			(layer "F.Fab")
			(hide yes)
			(effects
				(font
					(size 1 1)
					(thickness 0.15)
				)
			)
		)
		(property "License" "Apache-2.0"
			(at 0 0 90)
			(unlocked yes)
			(layer "F.Fab")
			(hide yes)
			(effects
				(font
					(size 1 1)
					(thickness 0.15)
				)
			)
		)
		(property "Author" "Antmicro"
			(at 0 0 90)
			(unlocked yes)
			(layer "F.Fab")
			(hide yes)
			(effects
				(font
					(size 1 1)
					(thickness 0.15)
				)
			)
		)
		(property "Val" "22u"
			(at 0 0 90)
			(unlocked yes)
			(layer "F.Fab")
			(hide yes)
			(effects
				(font
					(size 1 1)
					(thickness 0.15)
				)
			)
		)
		(property "Voltage" "16V"
			(at 0 0 90)
			(unlocked yes)
			(layer "F.Fab")
			(hide yes)
			(effects
				(font
					(size 1 1)
					(thickness 0.15)
				)
			)
		)
		(property "Dielectric" ""
			(at 0 0 90)
			(unlocked yes)
			(layer "F.Fab")
			(hide yes)
			(effects
				(font
					(size 1 1)
					(thickness 0.15)
				)
			)
		)
		(property "Public" "False"
			(at 0 0 90)
			(unlocked yes)
			(layer "F.Fab")
			(hide yes)
			(effects
				(font
					(size 1 1)
					(thickness 0.15)
				)
			)
		)
		(sheetname "/Power/")
		(sheetfile "power.kicad_sch")
		(attr smd)
		(fp_line
			(start -0.15 -0.55)
			(end 0.15 -0.55)
			(stroke
				(width 0.15)
				(type solid)
			)
			(layer "F.SilkS")
		)
		(fp_line
			(start -0.15 0.55)
			(end 0.15 0.55)
			(stroke
				(width 0.15)
				(type solid)
			)
			(layer "F.SilkS")
		)
		(fp_rect
			(start -1.25 -0.65)
			(end 1.25 0.65)
			(stroke
				(width 0.05)
				(type solid)
			)
			(fill no)
			(layer "F.CrtYd")
		)
		(fp_rect
			(start -0.8 -0.45)
			(end 0.8 0.45)
			(stroke
				(width 0.15)
				(type solid)
			)
			(fill no)
			(layer "F.Fab")
		)
		(pad "1" smd roundrect
			(at -0.7 0 90)
			(size 0.8 1.1)
			(layers "F.Cu" "F.Mask" "F.Paste")
			(roundrect_rratio 0.2)
			(net 28 "GND")
			(pintype "passive")
		)
		(pad "2" smd roundrect
			(at 0.7 0 90)
			(size 0.8 1.1)
			(layers "F.Cu" "F.Mask" "F.Paste")
			(roundrect_rratio 0.2)
			(net 255 "/Power/+3V3_OUT")
			(pintype "passive")
		)
	)
	(footprint "antmicro-footprints:VQFN-HR-9_2x1.5mm"
		(layer "F.Cu")
		(at 56.1 103.450001 -90)
		(property "Reference" "U3"
			(at -1.190001 0.92 180)
			(layer "F.SilkS")
			(effects
				(font
					(size 0.7 0.7)
					(thickness 0.14)
					(bold yes)
				)
				(justify right top)
			)
		)
		(property "Value" "TPS566231P"
			(at -1.45 2.45 90)
			(layer "F.Fab")
			(hide yes)
			(effects
				(font
					(size 0.7 0.7)
					(thickness 0.15)
				)
				(justify right top)
			)
		)
		(property "Datasheet" "https://www.ti.com/lit/ds/symlink/tps566231.pdf"
			(at 0 -0.045 90)
			(layer "F.Fab")
			(hide yes)
			(effects
				(font
					(size 0.7 0.7)
					(thickness 0.15)
				)
				(justify right top)
			)
		)
		(property "Description" "Switching Voltage Regulators 3-V to 18-V, 6-A synchronous buck converter"
			(at -1.45 3.65 90)
			(layer "F.Fab")
			(hide yes)
			(effects
				(font
					(size 0.7 0.7)
					(thickness 0.15)
				)
				(justify right top)
			)
		)
		(property "Manufacturer" "Texas Instruments"
			(at 0 0 270)
			(unlocked yes)
			(layer "F.Fab")
			(hide yes)
			(effects
				(font
					(size 1 1)
					(thickness 0.15)
				)
			)
		)
		(property "MPN" "TPS566231PRQFR"
			(at 0 0 270)
			(unlocked yes)
			(layer "F.Fab")
			(hide yes)
			(effects
				(font
					(size 1 1)
					(thickness 0.15)
				)
			)
		)
		(property "Author" "Antmicro"
			(at 0 0 270)
			(unlocked yes)
			(layer "F.Fab")
			(hide yes)
			(effects
				(font
					(size 1 1)
					(thickness 0.15)
				)
			)
		)
		(property "License" "Apache-2.0"
			(at 0 0 270)
			(unlocked yes)
			(layer "F.Fab")
			(hide yes)
			(effects
				(font
					(size 1 1)
					(thickness 0.15)
				)
			)
		)
		(sheetname "/Power/")
		(sheetfile "power.kicad_sch")
		(attr smd)
		(fp_line
			(start -1 0.945)
			(end -0.695 0.945)
			(stroke
				(width 0.15)
				(type solid)
			)
			(layer "F.SilkS")
		)
		(fp_line
			(start 1 0.945)
			(end 0.2 0.945)
			(stroke
				(width 0.15)
				(type solid)
			)
			(layer "F.SilkS")
		)
		(fp_line
			(start -1 -0.945)
			(end -0.695 -0.945)
			(stroke
				(width 0.15)
				(type solid)
			)
			(layer "F.SilkS")
		)
		(fp_line
			(start 1 -0.945)
			(end 0.695 -0.945)
			(stroke
				(width 0.15)
				(type solid)
			)
			(layer "F.SilkS")
		)
		(fp_circle
			(center -1.18 -0.77)
			(end -1.13 -0.77)
			(stroke
				(width 0.15)
				(type solid)
			)
			(fill yes)
			(layer "F.SilkS")
		)
		(fp_rect
			(start -1.3 -1.05)
			(end 1.3 1.05)
			(stroke
				(width 0.05)
				(type solid)
			)
			(fill no)
			(layer "F.CrtYd")
		)
		(fp_rect
			(start -1 -0.75)
			(end 1 0.75)
			(stroke
				(width 0.15)
				(type solid)
			)
			(fill no)
			(layer "F.Fab")
		)
		(pad "1" smd roundrect
			(at -0.925 -0.5 270)
			(size 0.55 0.25)
			(layers "F.Cu" "F.Mask" "F.Paste")
			(roundrect_rratio 0.125)
			(net 324 "/Power/1V88_VCC")
			(pinfunction "V_{CC}")
			(pintype "passive")
		)
		(pad "2" smd roundrect
			(at -0.925 0 270)
			(size 0.55 0.25)
			(layers "F.Cu" "F.Mask" "F.Paste")
			(roundrect_rratio 0.125)
			(net 330 "/Power/1V88_FB")
			(pinfunction "FB")
			(pintype "input")
		)
		(pad "3" smd roundrect
			(at -0.925 0.5 270)
			(size 0.55 0.25)
			(layers "F.Cu" "F.Mask" "F.Paste")
			(roundrect_rratio 0.125)
			(net 353 "/Power/1V88_EN")
			(pinfunction "EN")
			(pintype "input")
		)
		(pad "4" smd roundrect
			(at -0.25 0.45 270)
			(size 0.25 1)
			(layers "F.Cu" "F.Mask" "F.Paste")
			(roundrect_rratio 0.125)
			(net 28 "GND")
			(pinfunction "PGND")
			(pintype "power_in")
		)
		(pad "5" smd roundrect
			(at 0.925 0.5 270)
			(size 0.55 0.25)
			(layers "F.Cu" "F.Mask" "F.Paste")
			(roundrect_rratio 0.125)
			(net 314 "VCC")
			(pinfunction "V_{IN}")
			(pintype "power_in")
		)
		(pad "6" smd roundrect
			(at 0.925 0 270)
			(size 0.55 0.25)
			(layers "F.Cu" "F.Mask" "F.Paste")
			(roundrect_rratio 0.125)
			(net 314 "VCC")
			(pinfunction "V_{IN}")
			(pintype "passive")
		)
		(pad "7" smd roundrect
			(at 0.925 -0.5 270)
			(size 0.55 0.25)
			(layers "F.Cu" "F.Mask" "F.Paste")
			(roundrect_rratio 0.125)
			(net 323 "/Power/1V88_BST")
			(pinfunction "BST")
			(pintype "passive")
		)
		(pad "8" smd roundrect
			(at 0.25 -0.3 270)
			(size 0.25 1.3)
			(layers "F.Cu" "F.Mask" "F.Paste")
			(roundrect_rratio 0.125)
			(net 335 "/Power/1V88_SW")
			(pinfunction "SW")
			(pintype "power_out")
		)
		(pad "9" smd roundrect
			(at -0.25 -0.675 270)
			(size 0.25 0.55)
			(layers "F.Cu" "F.Mask" "F.Paste")
			(roundrect_rratio 0.125)
			(net 369 "/Power/1V88_PG")
			(pinfunction "PG")
			(pintype "passive")
		)
	)
	(footprint "antmicro-footprints:C_0603_1608Metric"
		(layer "F.Cu")
		(at 100.45 97.95)
		(descr "Capacitor SMD 0603")
		(tags "capacitor 0603")
		(property "Reference" "C160"
			(at 4.25 0.45 0)
			(layer "F.SilkS")
			(effects
				(font
					(size 0.7 0.7)
					(thickness 0.15)
				)
				(justify left bottom)
			)
		)
		(property "Value" "C_10u_10V_X7R_0603"
			(at -1.42757 1.770288 0)
			(layer "F.Fab")
			(hide yes)
			(effects
				(font
					(size 0.7 0.7)
					(thickness 0.15)
				)
				(justify left bottom)
			)
		)
		(property "Datasheet" "https://www.murata.com/products/productdetail?partno=GRM188Z71A106KA73%23"
			(at 0 0 0)
			(layer "F.Fab")
			(hide yes)
			(effects
				(font
					(size 1.27 1.27)
					(thickness 0.15)
				)
			)
		)
		(property "Description" "SMD Multilayer Ceramic Capacitor,  10µF, 10V, 0603, ±10%, X7R"
			(at 0 0 0)
			(layer "F.Fab")
			(hide yes)
			(effects
				(font
					(size 1.27 1.27)
					(thickness 0.15)
				)
			)
		)
		(property "MPN" "GRM188Z71A106KA73D"
			(at 0 0 0)
			(unlocked yes)
			(layer "F.Fab")
			(hide yes)
			(effects
				(font
					(size 1 1)
					(thickness 0.15)
				)
			)
		)
		(property "Val" "10u"
			(at 0 0 0)
			(unlocked yes)
			(layer "F.Fab")
			(hide yes)
			(effects
				(font
					(size 1 1)
					(thickness 0.15)
				)
			)
		)
		(property "Voltage" "10V"
			(at 0 0 0)
			(unlocked yes)
			(layer "F.Fab")
			(hide yes)
			(effects
				(font
					(size 1 1)
					(thickness 0.15)
				)
			)
		)
		(property "Dielectric" "X7R"
			(at 0 0 0)
			(unlocked yes)
			(layer "F.Fab")
			(hide yes)
			(effects
				(font
					(size 1 1)
					(thickness 0.15)
				)
			)
		)
		(property "Manufacturer" "Murata"
			(at 0 0 0)
			(unlocked yes)
			(layer "F.Fab")
			(hide yes)
			(effects
				(font
					(size 1 1)
					(thickness 0.15)
				)
			)
		)
		(property "License" "Apache-2.0"
			(at 0 0 0)
			(unlocked yes)
			(layer "F.Fab")
			(hide yes)
			(effects
				(font
					(size 1 1)
					(thickness 0.15)
				)
			)
		)
		(property "Author" "Antmicro"
			(at 0 0 0)
			(unlocked yes)
			(layer "F.Fab")
			(hide yes)
			(effects
				(font
					(size 1 1)
					(thickness 0.15)
				)
			)
		)
		(sheetname "/X710-AT2 power/")
		(sheetfile "x710-at2-power.kicad_sch")
		(attr smd)
		(fp_line
			(start -0.15 -0.4)
			(end 0.15 -0.4)
			(stroke
				(width 0.15)
				(type solid)
			)
			(layer "F.SilkS")
		)
		(fp_line
			(start -0.15 0.4)
			(end 0.15 0.4)
			(stroke
				(width 0.15)
				(type solid)
			)
			(layer "F.SilkS")
		)
		(fp_rect
			(start -1.25 -0.65)
			(end 1.25 0.65)
			(stroke
				(width 0.05)
				(type solid)
			)
			(fill no)
			(layer "F.CrtYd")
		)
		(fp_rect
			(start -0.8 -0.4)
			(end 0.8 0.4)
			(stroke
				(width 0.15)
				(type solid)
			)
			(fill no)
			(layer "F.Fab")
		)
		(pad "1" smd roundrect
			(at -0.7 0)
			(size 0.8 1)
			(layers "F.Cu" "F.Mask" "F.Paste")
			(roundrect_rratio 0.2)
			(net 28 "GND")
			(pintype "passive")
		)
		(pad "2" smd roundrect
			(at 0.7 0)
			(size 0.8 1)
			(layers "F.Cu" "F.Mask" "F.Paste")
			(roundrect_rratio 0.2)
			(net 1 "VCCA")
			(pintype "passive")
		)
	)
)
